%FSTAX23Y23*%
%MOIN*%
%SFA1B1*%

%IPPOS*%
%ADD9516C,0.039370*%
%LNgrandmaster-slotholes-1*%
%LPD*%
G54D9516*
X05934Y03977D02*
Y03898D01*
X06169Y03819D02*
X0607D01*
X06159Y04056D02*
X0608D01*
M02*